#ISCELL
  mstr_misc dns *
  *
#ISCELL
  pure_quanta quanta_title_block_c *
  *
#ISCELL
  standard offpage *
  page208_i1
#CELL
  pure_quanta q_res *
  page208_i10
#CELL
  pure_quanta q_res *
  page208_i11
#CELL
  pure_quanta q_res *
  page208_i12
#CELL
  pure_quanta q_res *
  page208_i13
#CELL
  pure_quanta q_res *
  page208_i14
#CELL
  pure_quanta q_res *
  page208_i15
#CELL
  pure_quanta q_res *
  page208_i16
#CELL
  pure_quanta q_res *
  page208_i17
#CELL
  pure_quanta q_res *
  page208_i18
#CELL
  pure_quanta q_res *
  page208_i19
#ISCELL
  standard offpage *
  page208_i2
#CELL
  pure_quanta q_res *
  page208_i20
#CELL
  pure_quanta q_res *
  page208_i21
#CELL
  pure_quanta q_res *
  page208_i22
#CELL
  pure_quanta q_res *
  page208_i23
#CELL
  pure_quanta q_res *
  page208_i24
#CELL
  pure_quanta q_res *
  page208_i25
#CELL
  pure_quanta q_res *
  page208_i26
#ISCELL
  standard offpage *
  page208_i27
#ISCELL
  standard offpage *
  page208_i28
#ISCELL
  standard offpage *
  page208_i29
#ISCELL
  standard offpage *
  page208_i3
#ISCELL
  standard offpage *
  page208_i30
#ISCELL
  standard offpage *
  page208_i31
#ISCELL
  standard offpage *
  page208_i32
#ISCELL
  standard offpage *
  page208_i33
#ISCELL
  standard offpage *
  page208_i34
#ISCELL
  standard offpage *
  page208_i35
#ISCELL
  standard offpage *
  page208_i36
#ISCELL
  standard offpage *
  page208_i37
#ISCELL
  standard offpage *
  page208_i38
#ISCELL
  standard offpage *
  page208_i39
#CELL
  pure_quanta q_res *
  page208_i4
#ISCELL
  standard offpage *
  page208_i40
#ISCELL
  standard offpage *
  page208_i41
#ISCELL
  standard offpage *
  page208_i42
#ISCELL
  standard offpage *
  page208_i43
#ISCELL
  standard offpage *
  page208_i44
#ISCELL
  standard offpage *
  page208_i45
#ISCELL
  standard offpage *
  page208_i46
#ISCELL
  standard offpage *
  page208_i47
#ISCELL
  standard offpage *
  page208_i48
#ISCELL
  standard offpage *
  page208_i49
#CELL
  pure_quanta q_res *
  page208_i5
#ISCELL
  logical_power universal_gnd *
  page208_i50
#CELL
  pure_quanta q_res *
  page208_i51
#CELL
  pure_quanta q_res *
  page208_i52
#CELL
  pure_quanta q_res *
  page208_i53
#CELL
  pure_quanta q_res *
  page208_i54
#CELL
  pure_quanta q_res *
  page208_i55
#CELL
  pure_quanta q_res *
  page208_i56
#CELL
  pure_quanta q_res *
  page208_i57
#CELL
  pure_quanta q_res *
  page208_i58
#CELL
  pure_quanta q_res *
  page208_i59
#CELL
  pure_quanta q_res *
  page208_i6
#ISCELL
  standard offpage *
  page208_i60
#ISCELL
  standard offpage *
  page208_i61
#ISCELL
  standard offpage *
  page208_i62
#ISCELL
  standard offpage *
  page208_i63
#ISCELL
  standard offpage *
  page208_i64
#ISCELL
  standard offpage *
  page208_i65
#CELL
  pure_quanta q_res *
  page208_i66
#ISCELL
  standard offpage *
  page208_i67
#CELL
  pure_quanta q_res *
  page208_i7
#CELL
  pure_quanta q_res *
  page208_i8
#CELL
  pure_quanta q_res *
  page208_i9
